(kicad_pcb
	(version 20241229)
	(generator "pcbnew")
	(generator_version "9.0")
	(general
		(thickness 1.6642)
		(legacy_teardrops no)
	)
	(paper "A3")
	(title_block
		(title "PolarFire SoM")
		(date "2025-07-22")
		(rev "1.1.4")
		(company "Antmicro Ltd")
		(comment 1 "www.antmicro.com")
		(comment 9 "footprints 250-253 of 470")
	)
	(layers
		(0 "F.Cu" mixed)
		(4 "In1.Cu" power)
		(6 "In2.Cu" signal)
		(8 "In3.Cu" power)
		(10 "In4.Cu" signal)
		(12 "In5.Cu" power)
		(14 "In6.Cu" power)
		(16 "In7.Cu" signal)
		(18 "In8.Cu" power)
		(20 "In9.Cu" signal)
		(22 "In10.Cu" power)
		(24 "In11.Cu" signal)
		(26 "In12.Cu" signal)
		(2 "B.Cu" mixed)
		(9 "F.Adhes" user "F.Adhesive")
		(11 "B.Adhes" user "B.Adhesive")
		(13 "F.Paste" user)
		(15 "B.Paste" user)
		(5 "F.SilkS" user "F.Silkscreen")
		(7 "B.SilkS" user "B.Silkscreen")
		(1 "F.Mask" user)
		(3 "B.Mask" user)
		(17 "Dwgs.User" user "User.Drawings")
		(19 "Cmts.User" user "User.Comments")
		(21 "Eco1.User" user "User.Eco1")
		(23 "Eco2.User" user "User.Eco2")
		(25 "Edge.Cuts" user)
		(27 "Margin" user)
		(31 "F.CrtYd" user "F.Courtyard")
		(29 "B.CrtYd" user "B.Courtyard")
		(35 "F.Fab" user)
		(33 "B.Fab" user)
	)
	(footprint "antmicro-footprints:C_0402_1005Metric"
		(layer "B.Cu")
		(at 197.299 124.784 -90)
		(descr "Capacitor SMD 0402")
		(tags "capacitor SMD 0402")
		(property "Reference" "C22"
			(at 0.741 0.924 135)
			(layer "B.SilkS")
			(effects
				(font
					(size 0.7 0.7)
					(thickness 0.15)
				)
				(justify left bottom mirror)
			)
		)
		(property "Value" "C_10u_0402"
			(at -1.022927 -2.155213 90)
			(layer "B.Fab")
			(hide yes)
			(effects
				(font
					(size 0.7 0.7)
					(thickness 0.15)
				)
				(justify left bottom mirror)
			)
		)
		(property "Datasheet" "https://www.yageo.com/en/Chart/Download/pdf/CC0402MRX5R5BB106"
			(at 0 0 270)
			(layer "F.Fab")
			(hide yes)
			(effects
				(font
					(size 1.27 1.27)
					(thickness 0.15)
				)
			)
		)
		(property "Description" "SMD Multilayer Ceramic Capacitor, 10 µF, 6.3 V, 0402 [1005 Metric], ± 20%, X5R, CC Series"
			(at 0 0 270)
			(layer "F.Fab")
			(hide yes)
			(effects
				(font
					(size 1.27 1.27)
					(thickness 0.15)
				)
			)
		)
		(property "Author" "Antmicro"
			(at 72.515 322.083 0)
			(layer "B.Fab")
			(hide yes)
			(effects
				(font
					(size 1 1)
					(thickness 0.15)
				)
				(justify mirror)
			)
		)
		(property "Dielectric" ""
			(at 72.515 322.083 0)
			(layer "B.Fab")
			(hide yes)
			(effects
				(font
					(size 1 1)
					(thickness 0.15)
				)
				(justify mirror)
			)
		)
		(property "License" "Apache-2.0"
			(at 72.515 322.083 0)
			(layer "B.Fab")
			(hide yes)
			(effects
				(font
					(size 1 1)
					(thickness 0.15)
				)
				(justify mirror)
			)
		)
		(property "MPN" "CC0402MRX5R5BB106"
			(at 72.515 322.083 0)
			(layer "B.Fab")
			(hide yes)
			(effects
				(font
					(size 1 1)
					(thickness 0.15)
				)
				(justify mirror)
			)
		)
		(property "Manufacturer" "YAGEO"
			(at 72.515 322.083 0)
			(layer "B.Fab")
			(hide yes)
			(effects
				(font
					(size 1 1)
					(thickness 0.15)
				)
				(justify mirror)
			)
		)
		(property "Public" ""
			(at 72.515 322.083 0)
			(layer "B.Fab")
			(hide yes)
			(effects
				(font
					(size 1 1)
					(thickness 0.15)
				)
				(justify mirror)
			)
		)
		(property "Val" "10u"
			(at 72.515 322.083 0)
			(layer "B.Fab")
			(hide yes)
			(effects
				(font
					(size 1 1)
					(thickness 0.15)
				)
				(justify mirror)
			)
		)
		(property "Voltage" ""
			(at 72.515 322.083 0)
			(layer "B.Fab")
			(hide yes)
			(effects
				(font
					(size 1 1)
					(thickness 0.15)
				)
				(justify mirror)
			)
		)
		(sheetname "/FPGA Supply/")
		(sheetfile "fpga-supply.kicad_sch")
		(attr smd)
		(fp_rect
			(start -0.925 0.47)
			(end 0.925 -0.47)
			(stroke
				(width 0.05)
				(type default)
			)
			(fill no)
			(layer "B.CrtYd")
		)
		(fp_line
			(start -0.494 0.25)
			(end 0.504 0.25)
			(stroke
				(width 0.15)
				(type solid)
			)
			(layer "B.Fab")
		)
		(fp_line
			(start 0.504 0.25)
			(end 0.504 -0.248)
			(stroke
				(width 0.15)
				(type solid)
			)
			(layer "B.Fab")
		)
		(fp_line
			(start -0.494 -0.248)
			(end -0.494 0.25)
			(stroke
				(width 0.15)
				(type solid)
			)
			(layer "B.Fab")
		)
		(fp_line
			(start 0.504 -0.248)
			(end -0.494 -0.248)
			(stroke
				(width 0.15)
				(type solid)
			)
			(layer "B.Fab")
		)
		(fp_text user "${REFERENCE}"
			(at -0.939 -4.599 90)
			(layer "B.Fab")
			(effects
				(font
					(size 0.7 0.7)
					(thickness 0.15)
				)
				(justify left bottom mirror)
			)
		)
		(fp_text user "Author: Antmicro"
			(at -0.939 -3.399 90)
			(layer "B.Fab")
			(effects
				(font
					(size 0.7 0.7)
					(thickness 0.15)
				)
				(justify left bottom mirror)
			)
		)
		(fp_text user "License: Apache-2.0"
			(at -0.939 -5.799 90)
			(layer "B.Fab")
			(effects
				(font
					(size 0.7 0.7)
					(thickness 0.15)
				)
				(justify left bottom mirror)
			)
		)
		(pad "1" smd roundrect
			(at -0.48 0 270)
			(size 0.59 0.64)
			(layers "B.Cu" "B.Mask" "B.Paste")
			(roundrect_rratio 0.25)
			(net 417 "GND")
			(pintype "passive")
		)
		(pad "2" smd roundrect
			(at 0.48 0 270)
			(size 0.59 0.64)
			(layers "B.Cu" "B.Mask" "B.Paste")
			(roundrect_rratio 0.25)
			(net 137 "SD_VDD")
			(pintype "passive")
		)
	)
	(footprint "antmicro-footprints:XSON-8_1x1.95mm_P0.5mm"
		(layer "B.Cu")
		(at 223.51 144.71 180)
		(property "Reference" "U30"
			(at -5.32 3.13 0)
			(layer "B.SilkS")
			(effects
				(font
					(size 0.7 0.7)
					(thickness 0.15)
				)
				(justify left bottom mirror)
			)
		)
		(property "Value" "NTS0102_XSON"
			(at 0 -2.2 0)
			(layer "B.Fab")
			(hide yes)
			(effects
				(font
					(size 0.7 0.7)
					(thickness 0.15)
				)
				(justify left bottom mirror)
			)
		)
		(property "Datasheet" "http://www.farnell.com/datasheets/1760723.pdf"
			(at 0 0 180)
			(layer "F.Fab")
			(hide yes)
			(effects
				(font
					(size 1.27 1.27)
					(thickness 0.15)
				)
			)
		)
		(property "Description" "Transceiver, 1.65 V to 3.6 V, XSON-8"
			(at 0 0 180)
			(layer "F.Fab")
			(hide yes)
			(effects
				(font
					(size 1.27 1.27)
					(thickness 0.15)
				)
			)
		)
		(property "Author" "Antmicro"
			(at 447.02 289.42 0)
			(layer "B.Fab")
			(hide yes)
			(effects
				(font
					(size 1 1)
					(thickness 0.15)
				)
				(justify mirror)
			)
		)
		(property "License" "Apache-2.0"
			(at 447.02 289.42 0)
			(layer "B.Fab")
			(hide yes)
			(effects
				(font
					(size 1 1)
					(thickness 0.15)
				)
				(justify mirror)
			)
		)
		(property "MPN" "NTS0102GT"
			(at 447.02 289.42 0)
			(layer "B.Fab")
			(hide yes)
			(effects
				(font
					(size 1 1)
					(thickness 0.15)
				)
				(justify mirror)
			)
		)
		(property "Manufacturer" "NXP"
			(at 447.02 289.42 0)
			(layer "B.Fab")
			(hide yes)
			(effects
				(font
					(size 1 1)
					(thickness 0.15)
				)
				(justify mirror)
			)
		)
		(sheetname "/FPGA MSSIO/")
		(sheetfile "fpga-mssio.kicad_sch")
		(attr smd)
		(fp_line
			(start 0.5 -1.1)
			(end -0.5 -1.1)
			(stroke
				(width 0.15)
				(type solid)
			)
			(layer "B.SilkS")
		)
		(fp_line
			(start -0.5 1.1)
			(end 0.5 1.1)
			(stroke
				(width 0.15)
				(type solid)
			)
			(layer "B.SilkS")
		)
		(fp_circle
			(center -0.75 1.1)
			(end -0.701 1.1)
			(stroke
				(width 0.15)
				(type solid)
			)
			(fill no)
			(layer "B.SilkS")
		)
		(fp_rect
			(start -0.8 1.2)
			(end 0.8 -1.2)
			(stroke
				(width 0.05)
				(type solid)
			)
			(fill no)
			(layer "B.CrtYd")
		)
		(fp_line
			(start 0.5305 1.001)
			(end 0.5305 -1)
			(stroke
				(width 0.15)
				(type solid)
			)
			(layer "B.Fab")
		)
		(fp_line
			(start 0.5305 -1)
			(end -0.5305 -1)
			(stroke
				(width 0.15)
				(type solid)
			)
			(layer "B.Fab")
		)
		(fp_line
			(start -0.5305 1.001)
			(end 0.5305 1.001)
			(stroke
				(width 0.15)
				(type solid)
			)
			(layer "B.Fab")
		)
		(fp_line
			(start -0.5305 -1)
			(end -0.5305 1.001)
			(stroke
				(width 0.15)
				(type solid)
			)
			(layer "B.Fab")
		)
		(fp_text user "${REFERENCE}"
			(at -0.527 -5.905 0)
			(layer "B.Fab")
			(effects
				(font
					(size 0.7 0.7)
					(thickness 0.15)
				)
				(justify left bottom mirror)
			)
		)
		(fp_text user "License: Apache-2.0"
			(at -0.527 -8.306 0)
			(layer "B.Fab")
			(effects
				(font
					(size 0.7 0.7)
					(thickness 0.15)
				)
				(justify left bottom mirror)
			)
		)
		(fp_text user "Author: Antmicro"
			(at -0.527 -7.105 0)
			(layer "B.Fab")
			(effects
				(font
					(size 0.7 0.7)
					(thickness 0.15)
				)
				(justify left bottom mirror)
			)
		)
		(pad "1" smd roundrect
			(at -0.45 0.75)
			(size 0.6 0.3)
			(layers "B.Cu" "B.Mask" "B.Paste")
			(roundrect_rratio 0.25)
			(net 117 "/FPGA MSSIO/PF_BT.RX")
			(pinfunction "B_{2}")
			(pintype "bidirectional")
		)
		(pad "2" smd roundrect
			(at -0.45 0.25)
			(size 0.6 0.25)
			(layers "B.Cu" "B.Mask" "B.Paste")
			(roundrect_rratio 0.25)
			(net 417 "GND")
			(pinfunction "GND")
			(pintype "power_in")
		)
		(pad "3" smd roundrect
			(at -0.45 -0.25)
			(size 0.6 0.25)
			(layers "B.Cu" "B.Mask" "B.Paste")
			(roundrect_rratio 0.25)
			(net 649 "VDD")
			(pinfunction "VCC_{A}")
			(pintype "power_in")
		)
		(pad "4" smd roundrect
			(at -0.45 -0.75)
			(size 0.6 0.3)
			(layers "B.Cu" "B.Mask" "B.Paste")
			(roundrect_rratio 0.25)
			(net 194 "/FPGA MSSIO/BT_UART_RX")
			(pinfunction "A_{2}")
			(pintype "bidirectional")
		)
		(pad "5" smd roundrect
			(at 0.45 -0.75)
			(size 0.6 0.3)
			(layers "B.Cu" "B.Mask" "B.Paste")
			(roundrect_rratio 0.25)
			(net 193 "/FPGA MSSIO/BT_UART_TX")
			(pinfunction "A_{1}")
			(pintype "bidirectional")
		)
		(pad "6" smd roundrect
			(at 0.45 -0.25)
			(size 0.6 0.25)
			(layers "B.Cu" "B.Mask" "B.Paste")
			(roundrect_rratio 0.25)
			(net 649 "VDD")
			(pinfunction "OE")
			(pintype "input")
		)
		(pad "7" smd roundrect
			(at 0.45 0.25)
			(size 0.6 0.25)
			(layers "B.Cu" "B.Mask" "B.Paste")
			(roundrect_rratio 0.25)
			(net 50 "+3V3")
			(pinfunction "VCC_{B}")
			(pintype "power_in")
		)
		(pad "8" smd roundrect
			(at 0.45 0.75)
			(size 0.6 0.3)
			(layers "B.Cu" "B.Mask" "B.Paste")
			(roundrect_rratio 0.25)
			(net 85 "/FPGA MSSIO/PF_BT.TX")
			(pinfunction "B_{1}")
			(pintype "bidirectional")
		)
	)
	(footprint "antmicro-footprints:R_0402_1005Metric"
		(layer "B.Cu")
		(at 208.25 133.35 180)
		(descr "Resistor SMD 0402")
		(tags "resistor SMD 0402")
		(property "Reference" "R40"
			(at 0.85 -0.4 0)
			(layer "B.SilkS")
			(effects
				(font
					(size 0.7 0.7)
					(thickness 0.15)
				)
				(justify left bottom mirror)
			)
		)
		(property "Value" "R_4k7_0402"
			(at -1.011843 -1.772047 0)
			(layer "B.Fab")
			(hide yes)
			(effects
				(font
					(size 0.7 0.7)
					(thickness 0.15)
				)
				(justify left bottom mirror)
			)
		)
		(property "Datasheet" "https://www.bourns.com/docs/product-datasheets/cr.pdf"
			(at 0 0 180)
			(layer "F.Fab")
			(hide yes)
			(effects
				(font
					(size 1.27 1.27)
					(thickness 0.15)
				)
			)
		)
		(property "Description" "SMD Chip Resistor, 4.7 kohm, ± 1%, 62.5 mW, 0402 [1005 Metric], Thick Film, General Purpose"
			(at 0 0 180)
			(layer "F.Fab")
			(hide yes)
			(effects
				(font
					(size 1.27 1.27)
					(thickness 0.15)
				)
			)
		)
		(property "Author" "Antmicro"
			(at 416.5 266.7 0)
			(layer "B.Fab")
			(hide yes)
			(effects
				(font
					(size 1 1)
					(thickness 0.15)
				)
				(justify mirror)
			)
		)
		(property "License" "Apache-2.0"
			(at 416.5 266.7 0)
			(layer "B.Fab")
			(hide yes)
			(effects
				(font
					(size 1 1)
					(thickness 0.15)
				)
				(justify mirror)
			)
		)
		(property "MPN" "CR0402-FX-4701GLF"
			(at 416.5 266.7 0)
			(layer "B.Fab")
			(hide yes)
			(effects
				(font
					(size 1 1)
					(thickness 0.15)
				)
				(justify mirror)
			)
		)
		(property "Manufacturer" "Bourns"
			(at 416.5 266.7 0)
			(layer "B.Fab")
			(hide yes)
			(effects
				(font
					(size 1 1)
					(thickness 0.15)
				)
				(justify mirror)
			)
		)
		(property "Public" ""
			(at 416.5 266.7 0)
			(layer "B.Fab")
			(hide yes)
			(effects
				(font
					(size 1 1)
					(thickness 0.15)
				)
				(justify mirror)
			)
		)
		(property "Tolerance" "1%"
			(at 416.5 266.7 0)
			(layer "B.Fab")
			(hide yes)
			(effects
				(font
					(size 1 1)
					(thickness 0.15)
				)
				(justify mirror)
			)
		)
		(property "Val" "4k7"
			(at 416.5 266.7 0)
			(layer "B.Fab")
			(hide yes)
			(effects
				(font
					(size 1 1)
					(thickness 0.15)
				)
				(justify mirror)
			)
		)
		(sheetname "/FPGA Config/")
		(sheetfile "fpga-config.kicad_sch")
		(attr smd)
		(fp_rect
			(start -0.925 0.47)
			(end 0.925 -0.47)
			(stroke
				(width 0.05)
				(type default)
			)
			(fill no)
			(layer "B.CrtYd")
		)
		(fp_rect
			(start -0.5 0.25)
			(end 0.5 -0.25)
			(stroke
				(width 0.15)
				(type solid)
			)
			(fill no)
			(layer "B.Fab")
		)
		(fp_text user "License: Apache-2.0"
			(at -0.95 -5.169 0)
			(layer "B.Fab")
			(effects
				(font
					(size 0.7 0.7)
					(thickness 0.15)
				)
				(justify left bottom mirror)
			)
		)
		(fp_text user "Author: Antmicro"
			(at -0.95 -4.169 0)
			(layer "B.Fab")
			(effects
				(font
					(size 0.7 0.7)
					(thickness 0.15)
				)
				(justify left bottom mirror)
			)
		)
		(fp_text user "${REFERENCE}"
			(at -0.95 -3.168 0)
			(layer "B.Fab")
			(effects
				(font
					(size 0.7 0.7)
					(thickness 0.15)
				)
				(justify left bottom mirror)
			)
		)
		(pad "1" smd roundrect
			(at -0.48 0 180)
			(size 0.59 0.64)
			(layers "B.Cu" "B.Mask" "B.Paste")
			(roundrect_rratio 0.25)
			(net 50 "+3V3")
			(pintype "passive")
		)
		(pad "2" smd roundrect
			(at 0.48 0 180)
			(size 0.59 0.64)
			(layers "B.Cu" "B.Mask" "B.Paste")
			(roundrect_rratio 0.25)
			(net 255 "Net-(U1D-IO_CFG_INTF)")
			(pintype "passive")
		)
	)
	(footprint "antmicro-footprints:C_0402_1005Metric"
		(layer "B.Cu")
		(at 197.04 130.824 90)
		(descr "Capacitor SMD 0402")
		(tags "capacitor SMD 0402")
		(property "Reference" "C10"
			(at 5.824 -9.59 90)
			(layer "B.SilkS")
			(effects
				(font
					(size 0.7 0.7)
					(thickness 0.15)
				)
				(justify right bottom mirror)
			)
		)
		(property "Value" "C_10u_0402"
			(at -1.022927 -2.155213 90)
			(layer "B.Fab")
			(hide yes)
			(effects
				(font
					(size 0.7 0.7)
					(thickness 0.15)
				)
				(justify right bottom mirror)
			)
		)
		(property "Datasheet" "https://www.yageo.com/en/Chart/Download/pdf/CC0402MRX5R5BB106"
			(at 0 0 90)
			(layer "F.Fab")
			(hide yes)
			(effects
				(font
					(size 1.27 1.27)
					(thickness 0.15)
				)
			)
		)
		(property "Description" "SMD Multilayer Ceramic Capacitor, 10 µF, 6.3 V, 0402 [1005 Metric], ± 20%, X5R, CC Series"
			(at 0 0 90)
			(layer "F.Fab")
			(hide yes)
			(effects
				(font
					(size 1.27 1.27)
					(thickness 0.15)
				)
			)
		)
		(property "Author" "Antmicro"
			(at 327.864 -66.216 0)
			(layer "B.Fab")
			(hide yes)
			(effects
				(font
					(size 1 1)
					(thickness 0.15)
				)
				(justify mirror)
			)
		)
		(property "Dielectric" ""
			(at 327.864 -66.216 0)
			(layer "B.Fab")
			(hide yes)
			(effects
				(font
					(size 1 1)
					(thickness 0.15)
				)
				(justify mirror)
			)
		)
		(property "License" "Apache-2.0"
			(at 327.864 -66.216 0)
			(layer "B.Fab")
			(hide yes)
			(effects
				(font
					(size 1 1)
					(thickness 0.15)
				)
				(justify mirror)
			)
		)
		(property "MPN" "CC0402MRX5R5BB106"
			(at 327.864 -66.216 0)
			(layer "B.Fab")
			(hide yes)
			(effects
				(font
					(size 1 1)
					(thickness 0.15)
				)
				(justify mirror)
			)
		)
		(property "Manufacturer" "YAGEO"
			(at 327.864 -66.216 0)
			(layer "B.Fab")
			(hide yes)
			(effects
				(font
					(size 1 1)
					(thickness 0.15)
				)
				(justify mirror)
			)
		)
		(property "Public" ""
			(at 327.864 -66.216 0)
			(layer "B.Fab")
			(hide yes)
			(effects
				(font
					(size 1 1)
					(thickness 0.15)
				)
				(justify mirror)
			)
		)
		(property "Val" "10u"
			(at 327.864 -66.216 0)
			(layer "B.Fab")
			(hide yes)
			(effects
				(font
					(size 1 1)
					(thickness 0.15)
				)
				(justify mirror)
			)
		)
		(property "Voltage" ""
			(at 327.864 -66.216 0)
			(layer "B.Fab")
			(hide yes)
			(effects
				(font
					(size 1 1)
					(thickness 0.15)
				)
				(justify mirror)
			)
		)
		(sheetname "/FPGA Supply/")
		(sheetfile "fpga-supply.kicad_sch")
		(attr smd)
		(fp_rect
			(start -0.925 0.47)
			(end 0.925 -0.47)
			(stroke
				(width 0.05)
				(type default)
			)
			(fill no)
			(layer "B.CrtYd")
		)
		(fp_line
			(start 0.504 -0.248)
			(end -0.494 -0.248)
			(stroke
				(width 0.15)
				(type solid)
			)
			(layer "B.Fab")
		)
		(fp_line
			(start -0.494 -0.248)
			(end -0.494 0.25)
			(stroke
				(width 0.15)
				(type solid)
			)
			(layer "B.Fab")
		)
		(fp_line
			(start 0.504 0.25)
			(end 0.504 -0.248)
			(stroke
				(width 0.15)
				(type solid)
			)
			(layer "B.Fab")
		)
		(fp_line
			(start -0.494 0.25)
			(end 0.504 0.25)
			(stroke
				(width 0.15)
				(type solid)
			)
			(layer "B.Fab")
		)
		(fp_text user "Author: Antmicro"
			(at -0.939 -3.399 270)
			(layer "B.Fab")
			(effects
				(font
					(size 0.7 0.7)
					(thickness 0.15)
				)
				(justify left bottom mirror)
			)
		)
		(fp_text user "${REFERENCE}"
			(at -0.939 -4.599 270)
			(layer "B.Fab")
			(effects
				(font
					(size 0.7 0.7)
					(thickness 0.15)
				)
				(justify left bottom mirror)
			)
		)
		(fp_text user "License: Apache-2.0"
			(at -0.939 -5.799 270)
			(layer "B.Fab")
			(effects
				(font
					(size 0.7 0.7)
					(thickness 0.15)
				)
				(justify left bottom mirror)
			)
		)
		(pad "1" smd roundrect
			(at -0.48 0 90)
			(size 0.59 0.64)
			(layers "B.Cu" "B.Mask" "B.Paste")
			(roundrect_rratio 0.25)
			(net 417 "GND")
			(pintype "passive")
		)
		(pad "2" smd roundrect
			(at 0.48 0 90)
			(size 0.59 0.64)
			(layers "B.Cu" "B.Mask" "B.Paste")
			(roundrect_rratio 0.25)
			(net 50 "+3V3")
			(pintype "passive")
		)
	)
)
